# T6G (Grand Teton) — schematic netlist excerpt (pin names and nets, part order shuffled) for the footprints in the layout excerpt that follows; sources: Cadence DE-HDL packaged netlist, KiCad conversion of 04192023_DAF0TMB3IC0_F0TG_MB_C_brd_V02_OCP.brd

R922  Q_RES  4.7K 5% EMPTY  pkg 0201LF  page 353 : A = P1V8_CPU1_RT_1D ; B = TEST2_RT_CPU1_P3
C940  Q_CAP_DIFFBUS  DIFF BUS_0.22UF 6.3V 20% X6S  pkg C0201  page 63 : \1\ = P5E_CPU0_P1_TX_C_DN<12> ; \2\ = P5E_CPU0_P1_TX_DN<12>

PL64  Q_INDUCTOR4P_14  150NH IND  pkg L_TLM117513Q-151QL_11X7-5XA  page 198
  \1\  = SW_PVDDCR_SOC_P0_SW2
  \2\  = IND_SOC_P0_CPL3
  \3\  = IND_SOC_P0_CPL2
  \4\  = PVDDCR_SOC_P0

C852  Q_CAP_DIFFBUS  DIFF BUS_0.22UF 6.3V 20% X6S  pkg C0201  page 64 : \1\ = P5E_CPU0_P2_TX_C_DN<8> ; \2\ = P5E_CPU0_P2_TX_DN<8>

(kicad_pcb
	(version 20260206)
	(generator "pcbnew")
	(generator_version "10.0")
	(general
		(thickness 1.6)
		(legacy_teardrops no)
	)
	(paper "A4")
	(title_block
		(title "04192023_DAF0TMB3IC0_F0TG_MB_C_brd_V02_OCP.brd")
		(comment 1 "Grand Teton / footprints 4791-4794 of 8354")
	)
	(layers
		(0 "F.Cu" signal "TOP")
		(4 "In1.Cu" signal "GND")
		(6 "In2.Cu" signal "IN1")
		(8 "In3.Cu" signal "GND1")
		(10 "In4.Cu" signal "IN2")
		(12 "In5.Cu" signal "GND2")
		(14 "In6.Cu" signal "IN3")
		(16 "In7.Cu" signal "GND3")
		(18 "In8.Cu" signal "VCC")
		(20 "In9.Cu" signal "VCC1")
		(22 "In10.Cu" signal "GND4")
		(24 "In11.Cu" signal "IN4")
		(26 "In12.Cu" signal "GND5")
		(28 "In13.Cu" signal "IN5")
		(30 "In14.Cu" signal "GND6")
		(32 "In15.Cu" signal "IN6")
		(34 "In16.Cu" signal "GND7")
		(2 "B.Cu" signal "BOTTOM")
		(9 "F.Adhes" user "F.Adhesive")
		(11 "B.Adhes" user "B.Adhesive")
		(13 "F.Paste" user "Package Geometry/Pastemask Top")
		(15 "B.Paste" user "Package Geometry/Pastemask Bottom")
		(5 "F.SilkS" user "Ref Des/Silkscreen Top")
		(7 "B.SilkS" user "Ref Des/Silkscreen Bottom")
		(1 "F.Mask" user "Board Geometry/Soldermask Top")
		(3 "B.Mask" user "Board Geometry/Soldermask Bottom")
		(17 "Dwgs.User" user "User.Drawings")
		(19 "Cmts.User" user "User.Comments")
		(21 "Eco1.User" user "User.Eco1")
		(23 "Eco2.User" user "User.Eco2")
		(25 "Edge.Cuts" user "Board Geometry/Outline")
		(27 "Margin" user)
		(31 "F.CrtYd" user "Package Geometry/Place Bound Top")
		(29 "B.CrtYd" user "Package Geometry/Place Bound Bottom")
		(35 "F.Fab" user "Ref Des/Assembly Top")
		(33 "B.Fab" user "Ref Des/Assembly Bottom")
	)
	(footprint ""
		(layer "F.Cu")
		(at 406.461976 -177.910998 180)
		(property "Reference" "PL64"
			(at -0.472694 5.858002 90)
			(unlocked yes)
			(layer "F.SilkS")
			(effects
				(font
					(size 0.7874 0.5842)
					(thickness 0.1524)
				)
				(justify left)
			)
		)
		(property "Value" ""
			(at 0 0 180)
			(layer "F.Fab")
			(effects
				(font
					(size 1.27 1.27)
				)
			)
		)
		(duplicate_pad_numbers_are_jumpers no)
		(fp_line
			(start 3.750056 5.500116)
			(end 3.750056 -5.500116)
			(stroke
				(width 0.1524)
				(type default)
			)
			(layer "F.SilkS")
		)
		(fp_line
			(start 3.750056 -5.500116)
			(end 2.393442 -5.500116)
			(stroke
				(width 0.1524)
				(type default)
			)
			(layer "F.SilkS")
		)
		(fp_line
			(start 2.393442 5.500116)
			(end 3.750056 5.500116)
			(stroke
				(width 0.1524)
				(type default)
			)
			(layer "F.SilkS")
		)
		(fp_line
			(start -2.393442 5.500116)
			(end -3.750056 5.500116)
			(stroke
				(width 0.1524)
				(type default)
			)
			(layer "F.SilkS")
		)
		(fp_line
			(start -3.750056 5.500116)
			(end -3.750056 -5.500116)
			(stroke
				(width 0.1524)
				(type default)
			)
			(layer "F.SilkS")
		)
		(fp_line
			(start -3.750056 -5.500116)
			(end -2.393442 -5.500116)
			(stroke
				(width 0.1524)
				(type default)
			)
			(layer "F.SilkS")
		)
		(fp_poly
			(pts
				(xy -3.9116 -4.249928) (xy -4.383024 -4.014216) (xy -4.383024 -4.48564)
			)
			(stroke
				(width 0)
				(type default)
			)
			(fill yes)
			(layer "F.SilkS")
		)
		(fp_line
			(start 3.750056 5.500116)
			(end 3.750056 -5.500116)
			(stroke
				(width 0.1)
				(type default)
			)
			(layer "F.Fab")
		)
		(fp_line
			(start 3.750056 -5.500116)
			(end -3.750056 -5.500116)
			(stroke
				(width 0.1)
				(type default)
			)
			(layer "F.Fab")
		)
		(fp_line
			(start -3.750056 5.500116)
			(end 3.750056 5.500116)
			(stroke
				(width 0.1)
				(type default)
			)
			(layer "F.Fab")
		)
		(fp_line
			(start -3.750056 -5.500116)
			(end -3.750056 5.500116)
			(stroke
				(width 0.1)
				(type default)
			)
			(layer "F.Fab")
		)
		(fp_poly
			(pts
				(xy -4.9276 -4.757928) (xy -4.9276 -3.741928) (xy -3.9116 -4.249928)
			)
			(stroke
				(width 0)
				(type default)
			)
			(fill yes)
			(layer "F.Fab")
		)
		(pad "1" smd rect
			(at 0 -4.249928 90)
			(size 2.413 4.5212)
			(layers "F.Cu" "F.Mask" "F.Paste")
			(net "SW_PVDDCR_SOC_P0_SW2")
		)
		(pad "2" smd rect
			(at 0 -1.175004 90)
			(size 1.3716 4.5212)
			(layers "F.Cu" "F.Mask" "F.Paste")
			(net "IND_SOC_P0_CPL3")
		)
		(pad "3" smd rect
			(at 0 1.175004 90)
			(size 1.3716 4.5212)
			(layers "F.Cu" "F.Mask" "F.Paste")
			(net "IND_SOC_P0_CPL2")
		)
		(pad "4" smd rect
			(at 0 4.249928 90)
			(size 2.413 4.5212)
			(layers "F.Cu" "F.Mask" "F.Paste")
			(net "PVDDCR_SOC_P0")
		)
	)
	(footprint ""
		(layer "F.Cu")
		(at 108.841794 -383.7432)
		(property "Reference" "R922"
			(at 0 0 0)
			(layer "F.SilkS")
			(hide yes)
			(effects
				(font
					(size 1.27 1.27)
				)
			)
		)
		(property "Value" ""
			(at 0 0 0)
			(layer "F.Fab")
			(effects
				(font
					(size 1.27 1.27)
				)
			)
		)
		(duplicate_pad_numbers_are_jumpers no)
		(fp_line
			(start -0.32512 -0.175006)
			(end 0.32512 -0.175006)
			(stroke
				(width 0.1)
				(type default)
			)
			(layer "F.Fab")
		)
		(fp_line
			(start -0.32512 0.175006)
			(end -0.32512 -0.175006)
			(stroke
				(width 0.1)
				(type default)
			)
			(layer "F.Fab")
		)
		(fp_line
			(start 0.32512 -0.175006)
			(end 0.32512 0.175006)
			(stroke
				(width 0.1)
				(type default)
			)
			(layer "F.Fab")
		)
		(fp_line
			(start 0.32512 0.175006)
			(end -0.32512 0.175006)
			(stroke
				(width 0.1)
				(type default)
			)
			(layer "F.Fab")
		)
		(pad "1" smd rect
			(at -0.2667 0)
			(size 0.3048 0.381)
			(layers "F.Cu" "F.Mask" "F.Paste")
			(net "P1V8_CPU1_RT_1D")
		)
		(pad "2" smd rect
			(at 0.2667 0 180)
			(size 0.3048 0.381)
			(layers "F.Cu" "F.Mask" "F.Paste")
			(net "TEST2_RT_CPU1_P3")
		)
	)
	(footprint ""
		(layer "F.Cu")
		(at 354.555044 -378.95403 -90)
		(property "Reference" "C940"
			(at 0 0 270)
			(layer "F.SilkS")
			(hide yes)
			(effects
				(font
					(size 1.27 1.27)
				)
			)
		)
		(property "Value" ""
			(at 0 0 270)
			(layer "F.Fab")
			(effects
				(font
					(size 1.27 1.27)
				)
			)
		)
		(duplicate_pad_numbers_are_jumpers no)
		(fp_line
			(start -0.299974 0.150114)
			(end -0.299974 -0.150114)
			(stroke
				(width 0.1)
				(type default)
			)
			(layer "F.Fab")
		)
		(fp_line
			(start 0.299974 0.150114)
			(end -0.299974 0.150114)
			(stroke
				(width 0.1)
				(type default)
			)
			(layer "F.Fab")
		)
		(fp_line
			(start -0.299974 -0.150114)
			(end 0.299974 -0.150114)
			(stroke
				(width 0.1)
				(type default)
			)
			(layer "F.Fab")
		)
		(fp_line
			(start 0.299974 -0.150114)
			(end 0.299974 0.150114)
			(stroke
				(width 0.1)
				(type default)
			)
			(layer "F.Fab")
		)
		(pad "1" smd rect
			(at -0.2667 0 270)
			(size 0.3048 0.381)
			(layers "F.Cu" "F.Mask" "F.Paste")
			(net "P5E_CPU0_P1_TX_C_DN<12>")
		)
		(pad "2" smd rect
			(at 0.2667 0 270)
			(size 0.3048 0.381)
			(layers "F.Cu" "F.Mask" "F.Paste")
			(net "P5E_CPU0_P1_TX_DN<12>")
		)
	)
	(footprint ""
		(layer "F.Cu")
		(at 413.14624 -381.41783 -90)
		(property "Reference" "C852"
			(at 0 0 270)
			(layer "F.SilkS")
			(hide yes)
			(effects
				(font
					(size 1.27 1.27)
				)
			)
		)
		(property "Value" ""
			(at 0 0 270)
			(layer "F.Fab")
			(effects
				(font
					(size 1.27 1.27)
				)
			)
		)
		(duplicate_pad_numbers_are_jumpers no)
		(fp_line
			(start -0.299974 0.150114)
			(end -0.299974 -0.150114)
			(stroke
				(width 0.1)
				(type default)
			)
			(layer "F.Fab")
		)
		(fp_line
			(start 0.299974 0.150114)
			(end -0.299974 0.150114)
			(stroke
				(width 0.1)
				(type default)
			)
			(layer "F.Fab")
		)
		(fp_line
			(start -0.299974 -0.150114)
			(end 0.299974 -0.150114)
			(stroke
				(width 0.1)
				(type default)
			)
			(layer "F.Fab")
		)
		(fp_line
			(start 0.299974 -0.150114)
			(end 0.299974 0.150114)
			(stroke
				(width 0.1)
				(type default)
			)
			(layer "F.Fab")
		)
		(pad "1" smd rect
			(at -0.2667 0 270)
			(size 0.3048 0.381)
			(layers "F.Cu" "F.Mask" "F.Paste")
			(net "P5E_CPU0_P2_TX_C_DN<8>")
		)
		(pad "2" smd rect
			(at 0.2667 0 270)
			(size 0.3048 0.381)
			(layers "F.Cu" "F.Mask" "F.Paste")
			(net "P5E_CPU0_P2_TX_DN<8>")
		)
	)
)
